# S9S_MB_2U (Grand Teton) — schematic netlist excerpt (pin names and nets, part order shuffled) for the footprints in the layout excerpt that follows; sources: Cadence DE-HDL packaged netlist, KiCad conversion of 03242023_DA0F0TMBIJ0_F0T_Motherboard_J_brd_V01_OCP.brd

R3472  Q_RES  0 5% EMPTY  pkg 0402LF  page 147 : A = GND ; B = GPU_WP_HW_CTRL_ISO
PR4228  Q_RES  0 5% EMPTY  pkg 0402LF  page 276 : A = PVCCFA_EHV_CPU0_FAULT ; B = GND

(kicad_pcb
	(version 20260206)
	(generator "pcbnew")
	(generator_version "10.0")
	(general
		(thickness 1.6)
		(legacy_teardrops no)
	)
	(paper "A4")
	(title_block
		(title "03242023_DA0F0TMBIJ0_F0T_Motherboard_J_brd_V01_OCP.brd")
		(comment 1 "Grand Teton / footprints 3387-3388 of 6105")
	)
	(layers
		(0 "F.Cu" signal "TOP")
		(4 "In1.Cu" signal "GND")
		(6 "In2.Cu" signal "IN1")
		(8 "In3.Cu" signal "GND1")
		(10 "In4.Cu" signal "IN2")
		(12 "In5.Cu" signal "GND2")
		(14 "In6.Cu" signal "IN3")
		(16 "In7.Cu" signal "GND3")
		(18 "In8.Cu" signal "VCC")
		(20 "In9.Cu" signal "VCC1")
		(22 "In10.Cu" signal "GND4")
		(24 "In11.Cu" signal "IN4")
		(26 "In12.Cu" signal "GND5")
		(28 "In13.Cu" signal "IN5")
		(30 "In14.Cu" signal "GND6")
		(32 "In15.Cu" signal "IN6")
		(34 "In16.Cu" signal "GND7")
		(2 "B.Cu" signal "BOTTOM")
		(9 "F.Adhes" user "F.Adhesive")
		(11 "B.Adhes" user "B.Adhesive")
		(13 "F.Paste" user "Package Geometry/Pastemask Top")
		(15 "B.Paste" user "Package Geometry/Pastemask Bottom")
		(5 "F.SilkS" user "Ref Des/Silkscreen Top")
		(7 "B.SilkS" user "Ref Des/Silkscreen Bottom")
		(1 "F.Mask" user "Board Geometry/Soldermask Top")
		(3 "B.Mask" user "Board Geometry/Soldermask Bottom")
		(17 "Dwgs.User" user "User.Drawings")
		(19 "Cmts.User" user "User.Comments")
		(21 "Eco1.User" user "User.Eco1")
		(23 "Eco2.User" user "User.Eco2")
		(25 "Edge.Cuts" user "Board Geometry/Outline")
		(27 "Margin" user)
		(31 "F.CrtYd" user "Package Geometry/Place Bound Top")
		(29 "B.CrtYd" user "Package Geometry/Place Bound Bottom")
		(35 "F.Fab" user "Ref Des/Assembly Top")
		(33 "B.Fab" user "Ref Des/Assembly Bottom")
	)
	(footprint ""
		(layer "F.Cu")
		(at 432.243992 -402.290534 180)
		(property "Reference" "R3472"
			(at 0 0 180)
			(layer "F.SilkS")
			(hide yes)
			(effects
				(font
					(size 1.27 1.27)
				)
			)
		)
		(property "Value" ""
			(at 0 0 180)
			(layer "F.Fab")
			(effects
				(font
					(size 1.27 1.27)
				)
			)
		)
		(duplicate_pad_numbers_are_jumpers no)
		(fp_line
			(start 0.7874 0.4064)
			(end -0.7874 0.4064)
			(stroke
				(width 0.1524)
				(type default)
			)
			(layer "F.SilkS")
		)
		(fp_line
			(start 0.7874 -0.4064)
			(end 0.7874 0.4064)
			(stroke
				(width 0.1524)
				(type default)
			)
			(layer "F.SilkS")
		)
		(fp_line
			(start -0.7874 0.4064)
			(end -0.7874 -0.4064)
			(stroke
				(width 0.1524)
				(type default)
			)
			(layer "F.SilkS")
		)
		(fp_line
			(start -0.7874 -0.4064)
			(end 0.7874 -0.4064)
			(stroke
				(width 0.1524)
				(type default)
			)
			(layer "F.SilkS")
		)
		(fp_line
			(start 0.67945 0.3048)
			(end 0.120396 0.3048)
			(stroke
				(width 0.1)
				(type default)
			)
			(layer "F.Fab")
		)
		(fp_line
			(start 0.67945 -0.3048)
			(end 0.67945 0.3048)
			(stroke
				(width 0.1)
				(type default)
			)
			(layer "F.Fab")
		)
		(fp_line
			(start 0.12065 -0.2794)
			(end 0.12065 -0.3048)
			(stroke
				(width 0.1)
				(type default)
			)
			(layer "F.Fab")
		)
		(fp_line
			(start 0.12065 -0.3048)
			(end 0.67945 -0.3048)
			(stroke
				(width 0.1)
				(type default)
			)
			(layer "F.Fab")
		)
		(fp_line
			(start 0.120396 0.3048)
			(end 0.120396 0.2794)
			(stroke
				(width 0.1)
				(type default)
			)
			(layer "F.Fab")
		)
		(fp_line
			(start 0.120396 0.2794)
			(end -0.12065 0.2794)
			(stroke
				(width 0.1)
				(type default)
			)
			(layer "F.Fab")
		)
		(fp_line
			(start -0.12065 0.3048)
			(end -0.67945 0.3048)
			(stroke
				(width 0.1)
				(type default)
			)
			(layer "F.Fab")
		)
		(fp_line
			(start -0.12065 0.2794)
			(end -0.12065 0.3048)
			(stroke
				(width 0.1)
				(type default)
			)
			(layer "F.Fab")
		)
		(fp_line
			(start -0.12065 -0.2794)
			(end 0.12065 -0.2794)
			(stroke
				(width 0.1)
				(type default)
			)
			(layer "F.Fab")
		)
		(fp_line
			(start -0.12065 -0.305054)
			(end -0.12065 -0.2794)
			(stroke
				(width 0.1)
				(type default)
			)
			(layer "F.Fab")
		)
		(fp_line
			(start -0.67945 0.3048)
			(end -0.67945 -0.305054)
			(stroke
				(width 0.1)
				(type default)
			)
			(layer "F.Fab")
		)
		(fp_line
			(start -0.67945 -0.305054)
			(end -0.12065 -0.305054)
			(stroke
				(width 0.1)
				(type default)
			)
			(layer "F.Fab")
		)
		(pad "1" smd circle
			(at -0.40005 0 180)
			(size 0 0)
			(layers "F.Cu" "F.Mask" "F.Paste")
			(net "GND")
		)
		(pad "2" smd circle
			(at 0.40005 0 180)
			(size 0 0)
			(layers "F.Cu" "F.Mask" "F.Paste")
			(net "GPU_WP_HW_CTRL_ISO")
		)
	)
	(footprint ""
		(layer "F.Cu")
		(at 420.93388 -156.632148 90)
		(property "Reference" "PR4228"
			(at 0 0 90)
			(layer "F.SilkS")
			(hide yes)
			(effects
				(font
					(size 1.27 1.27)
				)
			)
		)
		(property "Value" ""
			(at 0 0 90)
			(layer "F.Fab")
			(effects
				(font
					(size 1.27 1.27)
				)
			)
		)
		(duplicate_pad_numbers_are_jumpers no)
		(fp_line
			(start 0.7874 -0.4064)
			(end 0.7874 0.4064)
			(stroke
				(width 0.1524)
				(type default)
			)
			(layer "F.SilkS")
		)
		(fp_line
			(start -0.7874 -0.4064)
			(end 0.7874 -0.4064)
			(stroke
				(width 0.1524)
				(type default)
			)
			(layer "F.SilkS")
		)
		(fp_line
			(start 0.7874 0.4064)
			(end -0.7874 0.4064)
			(stroke
				(width 0.1524)
				(type default)
			)
			(layer "F.SilkS")
		)
		(fp_line
			(start -0.7874 0.4064)
			(end -0.7874 -0.4064)
			(stroke
				(width 0.1524)
				(type default)
			)
			(layer "F.SilkS")
		)
		(fp_line
			(start -0.12065 -0.305054)
			(end -0.12065 -0.2794)
			(stroke
				(width 0.1)
				(type default)
			)
			(layer "F.Fab")
		)
		(fp_line
			(start -0.67945 -0.305054)
			(end -0.12065 -0.305054)
			(stroke
				(width 0.1)
				(type default)
			)
			(layer "F.Fab")
		)
		(fp_line
			(start 0.67945 -0.3048)
			(end 0.67945 0.3048)
			(stroke
				(width 0.1)
				(type default)
			)
			(layer "F.Fab")
		)
		(fp_line
			(start 0.12065 -0.3048)
			(end 0.67945 -0.3048)
			(stroke
				(width 0.1)
				(type default)
			)
			(layer "F.Fab")
		)
		(fp_line
			(start 0.12065 -0.2794)
			(end 0.12065 -0.3048)
			(stroke
				(width 0.1)
				(type default)
			)
			(layer "F.Fab")
		)
		(fp_line
			(start -0.12065 -0.2794)
			(end 0.12065 -0.2794)
			(stroke
				(width 0.1)
				(type default)
			)
			(layer "F.Fab")
		)
		(fp_line
			(start 0.120396 0.2794)
			(end -0.12065 0.2794)
			(stroke
				(width 0.1)
				(type default)
			)
			(layer "F.Fab")
		)
		(fp_line
			(start -0.12065 0.2794)
			(end -0.12065 0.3048)
			(stroke
				(width 0.1)
				(type default)
			)
			(layer "F.Fab")
		)
		(fp_line
			(start 0.67945 0.3048)
			(end 0.120396 0.3048)
			(stroke
				(width 0.1)
				(type default)
			)
			(layer "F.Fab")
		)
		(fp_line
			(start 0.120396 0.3048)
			(end 0.120396 0.2794)
			(stroke
				(width 0.1)
				(type default)
			)
			(layer "F.Fab")
		)
		(fp_line
			(start -0.12065 0.3048)
			(end -0.67945 0.3048)
			(stroke
				(width 0.1)
				(type default)
			)
			(layer "F.Fab")
		)
		(fp_line
			(start -0.67945 0.3048)
			(end -0.67945 -0.305054)
			(stroke
				(width 0.1)
				(type default)
			)
			(layer "F.Fab")
		)
		(pad "1" smd circle
			(at -0.40005 0 90)
			(size 0 0)
			(layers "F.Cu" "F.Mask" "F.Paste")
			(net "PVCCFA_EHV_CPU0_FAULT")
		)
		(pad "2" smd circle
			(at 0.40005 0 90)
			(size 0 0)
			(layers "F.Cu" "F.Mask" "F.Paste")
			(net "GND")
		)
	)
)
